(kicad_pcb
	(version 20260206)
	(generator "pcbnew")
	(generator_version "10.0")
	(general
		(thickness 1.6)
		(legacy_teardrops no)
	)
	(paper "A4")
	(title_block
		(title "Bryce Canyon_F.DPB_16315-1-OCP.brd")
		(comment 1 "Bryce Canyon / footprints 844-852 of 2223")
	)
	(layers
		(0 "F.Cu" signal "TOP")
		(4 "In1.Cu" signal "L2GND")
		(6 "In2.Cu" signal "L3")
		(8 "In3.Cu" signal "L4GND")
		(10 "In4.Cu" signal "L5")
		(12 "In5.Cu" signal "L6VCC")
		(14 "In6.Cu" signal "L7VCC")
		(16 "In7.Cu" signal "L8")
		(18 "In8.Cu" signal "L9GND")
		(20 "In9.Cu" signal "L10")
		(22 "In10.Cu" signal "L11GND")
		(2 "B.Cu" signal "BOTTOM")
		(9 "F.Adhes" user "F.Adhesive")
		(11 "B.Adhes" user "B.Adhesive")
		(13 "F.Paste" user "Package Geometry/Pastemask Top")
		(15 "B.Paste" user "Package Geometry/Pastemask Bottom")
		(5 "F.SilkS" user "Ref Des/Silkscreen Top")
		(7 "B.SilkS" user "Ref Des/Silkscreen Bottom")
		(1 "F.Mask" user "Board Geometry/Soldermask Top")
		(3 "B.Mask" user "Board Geometry/Soldermask Bottom")
		(17 "Dwgs.User" user "User.Drawings")
		(19 "Cmts.User" user "User.Comments")
		(21 "Eco1.User" user "User.Eco1")
		(23 "Eco2.User" user "User.Eco2")
		(25 "Edge.Cuts" user "Board Geometry/Outline")
		(27 "Margin" user)
		(31 "F.CrtYd" user "Package Geometry/Place Bound Top")
		(29 "B.CrtYd" user "Package Geometry/Place Bound Bottom")
		(35 "F.Fab" user "Ref Des/Assembly Top")
		(33 "B.Fab" user "Ref Des/Assembly Bottom")
	)
	(footprint ""
		(layer "F.Cu")
		(at 24.240998 -304.462942 180)
		(property "Reference" "C515"
			(at 0 0 180)
			(layer "F.SilkS")
			(hide yes)
			(effects
				(font
					(size 1.27 1.27)
				)
			)
		)
		(property "Value" "SC1U25V3KX-GP"
			(at 0 -2.8194 180)
			(unlocked yes)
			(layer "F.Fab")
			(hide yes)
			(effects
				(font
					(size 1.016 1.016)
					(thickness 0.1524)
				)
			)
		)
		(property "Device Type" "C603H36"
			(at 0 -4.3434 180)
			(unlocked yes)
			(layer "F.Fab")
			(hide yes)
			(effects
				(font
					(size 1.016 1.016)
					(thickness 0.1524)
				)
			)
		)
		(duplicate_pad_numbers_are_jumpers no)
		(fp_line
			(start 0.508 0)
			(end -0.508 0)
			(stroke
				(width 0.2032)
				(type default)
			)
			(layer "F.SilkS")
		)
		(fp_rect
			(start -0.5842 1.3335)
			(end 0.5842 -1.3335)
			(stroke
				(width 0)
				(type default)
			)
			(fill no)
			(layer "F.CrtYd")
		)
		(fp_rect
			(start -0.5842 1.3335)
			(end 0.5842 -1.3335)
			(stroke
				(width 0)
				(type default)
			)
			(fill no)
			(layer "F.Fab")
		)
		(pad "1" smd custom
			(at 0 -0.762 180)
			(size 0.2159 0.2159)
			(layers "F.Cu" "F.Mask" "F.Paste")
			(net "P12V_HDD0")
			(options
				(clearance outline)
				(anchor circle)
			)
			(primitives
				(gr_poly
					(pts
						(arc
							(start -0.3302 -0.4318)
							(mid -0.402042 -0.402042)
							(end -0.4318 -0.3302)
						)
						(arc
							(start -0.4318 0.3302)
							(mid -0.402042 0.402042)
							(end -0.3302 0.4318)
						)
						(arc
							(start 0.3302 0.4318)
							(mid 0.402042 0.402042)
							(end 0.4318 0.3302)
						)
						(arc
							(start 0.4318 -0.3302)
							(mid 0.402042 -0.402042)
							(end 0.3302 -0.4318)
						)
					)
					(width 0)
					(fill yes)
				)
			)
		)
		(pad "2" smd custom
			(at 0 0.762 180)
			(size 0.2159 0.2159)
			(layers "F.Cu" "F.Mask" "F.Paste")
			(net "GND")
			(options
				(clearance outline)
				(anchor circle)
			)
			(primitives
				(gr_poly
					(pts
						(arc
							(start -0.3302 -0.4318)
							(mid -0.402042 -0.402042)
							(end -0.4318 -0.3302)
						)
						(arc
							(start -0.4318 0.3302)
							(mid -0.402042 0.402042)
							(end -0.3302 0.4318)
						)
						(arc
							(start 0.3302 0.4318)
							(mid 0.402042 0.402042)
							(end 0.4318 0.3302)
						)
						(arc
							(start 0.4318 -0.3302)
							(mid 0.402042 -0.402042)
							(end 0.3302 -0.4318)
						)
					)
					(width 0)
					(fill yes)
				)
			)
		)
	)
	(footprint ""
		(layer "F.Cu")
		(at 280.080466 22.062948 90)
		(property "Reference" "R1134"
			(at 0 0 90)
			(layer "F.SilkS")
			(hide yes)
			(effects
				(font
					(size 1.27 1.27)
				)
			)
		)
		(property "Value" "2K2R2F-GP"
			(at 0.064008 -3.993896 90)
			(unlocked yes)
			(layer "F.Fab")
			(hide yes)
			(effects
				(font
					(size 1.016 1.016)
					(thickness 0.1524)
				)
			)
		)
		(property "Device Type" "R402H16"
			(at 0.064008 -5.517896 90)
			(unlocked yes)
			(layer "F.Fab")
			(hide yes)
			(effects
				(font
					(size 1.016 1.016)
					(thickness 0.1524)
				)
			)
		)
		(duplicate_pad_numbers_are_jumpers no)
		(fp_line
			(start 0.508 -0.9398)
			(end -0.508 -0.9398)
			(stroke
				(width 0.1524)
				(type default)
			)
			(layer "F.SilkS")
		)
		(fp_line
			(start -0.508 -0.9398)
			(end -0.508 0.9398)
			(stroke
				(width 0.1524)
				(type default)
			)
			(layer "F.SilkS")
		)
		(fp_rect
			(start -0.508 0.9398)
			(end 0.508 -0.9398)
			(stroke
				(width 0)
				(type default)
			)
			(fill no)
			(layer "F.CrtYd")
		)
		(fp_rect
			(start -0.508 0.9398)
			(end 0.508 -0.9398)
			(stroke
				(width 0)
				(type default)
			)
			(fill no)
			(layer "F.Fab")
		)
		(pad "1" smd custom
			(at 0 -0.4445 90)
			(size 0.1397 0.1397)
			(layers "F.Cu" "F.Mask" "F.Paste")
			(net "P12V_IN")
			(options
				(clearance outline)
				(anchor circle)
			)
			(primitives
				(gr_poly
					(pts
						(arc
							(start -0.1778 -0.2794)
							(mid -0.249642 -0.249642)
							(end -0.2794 -0.1778)
						)
						(arc
							(start -0.2794 0.1778)
							(mid -0.249642 0.249642)
							(end -0.1778 0.2794)
						)
						(arc
							(start 0.1778 0.2794)
							(mid 0.249642 0.249642)
							(end 0.2794 0.1778)
						)
						(arc
							(start 0.2794 -0.1778)
							(mid 0.249642 -0.249642)
							(end 0.1778 -0.2794)
						)
					)
					(width 0)
					(fill yes)
				)
			)
		)
		(pad "2" smd custom
			(at 0 0.4445 90)
			(size 0.1397 0.1397)
			(layers "F.Cu" "F.Mask" "F.Paste")
			(net "DPB_PWR_BTN_A")
			(options
				(clearance outline)
				(anchor circle)
			)
			(primitives
				(gr_poly
					(pts
						(arc
							(start -0.1778 -0.2794)
							(mid -0.249642 -0.249642)
							(end -0.2794 -0.1778)
						)
						(arc
							(start -0.2794 0.1778)
							(mid -0.249642 0.249642)
							(end -0.1778 0.2794)
						)
						(arc
							(start 0.1778 0.2794)
							(mid 0.249642 0.249642)
							(end 0.2794 0.1778)
						)
						(arc
							(start 0.2794 -0.1778)
							(mid 0.249642 -0.249642)
							(end 0.1778 -0.2794)
						)
					)
					(width 0)
					(fill yes)
				)
			)
		)
	)
	(footprint ""
		(layer "F.Cu")
		(at 412.937452 -65.039494 -90)
		(property "Reference" "R893"
			(at 0 0 270)
			(layer "F.SilkS")
			(hide yes)
			(effects
				(font
					(size 1.27 1.27)
				)
			)
		)
		(property "Value" "220R3F-1-GP"
			(at -0.0254 -2.5146 270)
			(unlocked yes)
			(layer "F.Fab")
			(hide yes)
			(effects
				(font
					(size 1.016 1.016)
					(thickness 0.1524)
				)
			)
		)
		(property "Device Type" "R603H22"
			(at -0.0254 -4.0386 270)
			(unlocked yes)
			(layer "F.Fab")
			(hide yes)
			(effects
				(font
					(size 1.016 1.016)
					(thickness 0.1524)
				)
			)
		)
		(duplicate_pad_numbers_are_jumpers no)
		(fp_line
			(start -0.4826 0)
			(end -0.2032 0)
			(stroke
				(width 0.2032)
				(type default)
			)
			(layer "F.SilkS")
		)
		(fp_line
			(start 0.2032 0)
			(end 0.4826 0)
			(stroke
				(width 0.2032)
				(type default)
			)
			(layer "F.SilkS")
		)
		(fp_rect
			(start -0.5842 1.3335)
			(end 0.5842 -1.3335)
			(stroke
				(width 0)
				(type default)
			)
			(fill no)
			(layer "F.CrtYd")
		)
		(fp_rect
			(start -0.5842 1.3335)
			(end 0.5842 -1.3335)
			(stroke
				(width 0)
				(type default)
			)
			(fill no)
			(layer "F.Fab")
		)
		(pad "1" smd custom
			(at 0 -0.762 270)
			(size 0.2159 0.2159)
			(layers "F.Cu" "F.Mask" "F.Paste")
			(net "HDD_PRSNT_33")
			(options
				(clearance outline)
				(anchor circle)
			)
			(primitives
				(gr_poly
					(pts
						(arc
							(start -0.3302 -0.4318)
							(mid -0.402042 -0.402042)
							(end -0.4318 -0.3302)
						)
						(arc
							(start -0.4318 0.3302)
							(mid -0.402042 0.402042)
							(end -0.3302 0.4318)
						)
						(arc
							(start 0.3302 0.4318)
							(mid 0.402042 0.402042)
							(end 0.4318 0.3302)
						)
						(arc
							(start 0.4318 -0.3302)
							(mid 0.402042 -0.402042)
							(end 0.3302 -0.4318)
						)
					)
					(width 0)
					(fill yes)
				)
			)
		)
		(pad "2" smd custom
			(at 0 0.762 270)
			(size 0.2159 0.2159)
			(layers "F.Cu" "F.Mask" "F.Paste")
			(net "DRIVE_A_33_INS")
			(options
				(clearance outline)
				(anchor circle)
			)
			(primitives
				(gr_poly
					(pts
						(arc
							(start -0.3302 -0.4318)
							(mid -0.402042 -0.402042)
							(end -0.4318 -0.3302)
						)
						(arc
							(start -0.4318 0.3302)
							(mid -0.402042 0.402042)
							(end -0.3302 0.4318)
						)
						(arc
							(start 0.3302 0.4318)
							(mid 0.402042 0.402042)
							(end 0.4318 0.3302)
						)
						(arc
							(start 0.4318 -0.3302)
							(mid 0.402042 -0.402042)
							(end 0.3302 -0.4318)
						)
					)
					(width 0)
					(fill yes)
				)
			)
		)
	)
	(footprint ""
		(layer "F.Cu")
		(at 419.389052 -47.749968 -90)
		(property "Reference" "VIA31"
			(at 0 0 270)
			(layer "F.SilkS")
			(hide yes)
			(effects
				(font
					(size 1.27 1.27)
				)
			)
		)
		(property "Value" "100OHM-8L-1D6MM-L18L16-GP"
			(at -3.7211 -4.5085 270)
			(unlocked yes)
			(layer "F.Fab")
			(hide yes)
			(effects
				(font
					(size 1.016 1.016)
					(thickness 0.1524)
				)
			)
		)
		(property "Device Type" "VIA-PCIE-4P-394076"
			(at -3.7211 -6.0325 270)
			(unlocked yes)
			(layer "F.Fab")
			(hide yes)
			(effects
				(font
					(size 1.016 1.016)
					(thickness 0.1524)
				)
			)
		)
		(duplicate_pad_numbers_are_jumpers no)
		(fp_rect
			(start -1.9685 0.381)
			(end 1.9685 -0.381)
			(stroke
				(width 0)
				(type default)
			)
			(fill no)
			(layer "F.CrtYd")
		)
		(fp_rect
			(start -1.9685 0.381)
			(end 1.9685 -0.381)
			(stroke
				(width 0)
				(type default)
			)
			(fill no)
			(layer "F.Fab")
		)
		(pad "1" thru_hole circle
			(at -1.5875 0 270)
			(size 0.508 0.508)
			(drill 0.254)
			(layers "*.Cu" "*.Mask")
			(remove_unused_layers no)
			(net "GND")
			(clearance 0.127)
			(thermal_gap 0.127)
		)
		(pad "2" thru_hole circle
			(at -0.5715 0 270)
			(size 0.508 0.508)
			(drill 0.254)
			(layers "*.Cu" "*.Mask")
			(remove_unused_layers no)
			(net "PHY_DRV_A_TO_SCC_A_33_DP")
			(clearance 0.127)
			(thermal_gap 0.127)
		)
		(pad "3" thru_hole circle
			(at 0.5715 0 270)
			(size 0.508 0.508)
			(drill 0.254)
			(layers "*.Cu" "*.Mask")
			(remove_unused_layers no)
			(net "PHY_DRV_A_TO_SCC_A_33_DN")
			(clearance 0.127)
			(thermal_gap 0.127)
		)
		(pad "4" thru_hole circle
			(at 1.5875 0 270)
			(size 0.508 0.508)
			(drill 0.254)
			(layers "*.Cu" "*.Mask")
			(remove_unused_layers no)
			(net "GND")
			(clearance 0.127)
			(thermal_gap 0.127)
		)
	)
	(footprint ""
		(layer "F.Cu")
		(at 35.543998 -68.747894)
		(property "Reference" "TP122"
			(at 0 0 0)
			(layer "F.SilkS")
			(hide yes)
			(effects
				(font
					(size 1.27 1.27)
				)
			)
		)
		(property "Value" "TPAD32-GP"
			(at -0.0508 -1.6764 0)
			(unlocked yes)
			(layer "F.Fab")
			(hide yes)
			(effects
				(font
					(size 1.016 1.016)
					(thickness 0.1524)
				)
			)
		)
		(property "Device Type" "TPAD32"
			(at -0.0508 -3.2004 0)
			(unlocked yes)
			(layer "F.Fab")
			(hide yes)
			(effects
				(font
					(size 1.016 1.016)
					(thickness 0.1524)
				)
			)
		)
		(duplicate_pad_numbers_are_jumpers no)
		(fp_poly
			(pts
				(arc
					(start 0.4064 0)
					(mid -0.4064 0)
					(end 0.4064 0)
				)
			)
			(stroke
				(width 0)
				(type default)
			)
			(fill no)
			(layer "F.CrtYd")
		)
		(fp_poly
			(pts
				(arc
					(start 0.7112 0)
					(mid -0.7112 0)
					(end 0.7112 0)
				)
			)
			(stroke
				(width 0)
				(type default)
			)
			(fill no)
			(layer "F.Fab")
		)
		(pad "1" smd circle
			(at 0 0)
			(size 0.8128 0.8128)
			(layers "F.Cu" "F.Mask" "F.Paste")
			(net "ACT_HDD_24")
		)
	)
	(footprint ""
		(layer "F.Cu")
		(at 223.421194 -349.439484 -90)
		(property "Reference" "R21"
			(at 0 0 270)
			(layer "F.SilkS")
			(hide yes)
			(effects
				(font
					(size 1.27 1.27)
				)
			)
		)
		(property "Value" "0R2J-2-GP"
			(at 0.064008 -3.993896 270)
			(unlocked yes)
			(layer "F.Fab")
			(hide yes)
			(effects
				(font
					(size 1.016 1.016)
					(thickness 0.1524)
				)
			)
		)
		(property "Device Type" "R402H16"
			(at 0.064008 -5.517896 270)
			(unlocked yes)
			(layer "F.Fab")
			(hide yes)
			(effects
				(font
					(size 1.016 1.016)
					(thickness 0.1524)
				)
			)
		)
		(duplicate_pad_numbers_are_jumpers no)
		(fp_line
			(start -0.508 -0.9398)
			(end -0.508 0.9398)
			(stroke
				(width 0.1524)
				(type default)
			)
			(layer "F.SilkS")
		)
		(fp_line
			(start 0.508 -0.9398)
			(end -0.508 -0.9398)
			(stroke
				(width 0.1524)
				(type default)
			)
			(layer "F.SilkS")
		)
		(fp_rect
			(start -0.508 0.9398)
			(end 0.508 -0.9398)
			(stroke
				(width 0)
				(type default)
			)
			(fill no)
			(layer "F.CrtYd")
		)
		(fp_rect
			(start -0.508 0.9398)
			(end 0.508 -0.9398)
			(stroke
				(width 0)
				(type default)
			)
			(fill no)
			(layer "F.Fab")
		)
		(pad "1" smd custom
			(at 0 -0.4445 270)
			(size 0.1397 0.1397)
			(layers "F.Cu" "F.Mask" "F.Paste")
			(net "VOL_SEN_SCL")
			(options
				(clearance outline)
				(anchor circle)
			)
			(primitives
				(gr_poly
					(pts
						(arc
							(start -0.1778 -0.2794)
							(mid -0.249642 -0.249642)
							(end -0.2794 -0.1778)
						)
						(arc
							(start -0.2794 0.1778)
							(mid -0.249642 0.249642)
							(end -0.1778 0.2794)
						)
						(arc
							(start 0.1778 0.2794)
							(mid 0.249642 0.249642)
							(end 0.2794 0.1778)
						)
						(arc
							(start 0.2794 -0.1778)
							(mid 0.249642 -0.249642)
							(end 0.1778 -0.2794)
						)
					)
					(width 0)
					(fill yes)
				)
			)
		)
		(pad "2" smd custom
			(at 0 0.4445 270)
			(size 0.1397 0.1397)
			(layers "F.Cu" "F.Mask" "F.Paste")
			(net "I2C_DPB_A_SCL_BUF")
			(options
				(clearance outline)
				(anchor circle)
			)
			(primitives
				(gr_poly
					(pts
						(arc
							(start -0.1778 -0.2794)
							(mid -0.249642 -0.249642)
							(end -0.2794 -0.1778)
						)
						(arc
							(start -0.2794 0.1778)
							(mid -0.249642 0.249642)
							(end -0.1778 0.2794)
						)
						(arc
							(start 0.1778 0.2794)
							(mid 0.249642 0.249642)
							(end 0.2794 0.1778)
						)
						(arc
							(start 0.2794 -0.1778)
							(mid 0.249642 -0.249642)
							(end 0.1778 -0.2794)
						)
					)
					(width 0)
					(fill yes)
				)
			)
		)
	)
	(footprint ""
		(layer "F.Cu")
		(at 394.56995 -164.062918 -90)
		(property "Reference" "R597"
			(at 0 0 270)
			(layer "F.SilkS")
			(hide yes)
			(effects
				(font
					(size 1.27 1.27)
				)
			)
		)
		(property "Value" "4K7R2J-2-GP"
			(at 0.064008 -3.993896 270)
			(unlocked yes)
			(layer "F.Fab")
			(hide yes)
			(effects
				(font
					(size 1.016 1.016)
					(thickness 0.1524)
				)
			)
		)
		(property "Device Type" "R402H16"
			(at 0.064008 -5.517896 270)
			(unlocked yes)
			(layer "F.Fab")
			(hide yes)
			(effects
				(font
					(size 1.016 1.016)
					(thickness 0.1524)
				)
			)
		)
		(duplicate_pad_numbers_are_jumpers no)
		(fp_line
			(start -0.508 -0.9398)
			(end -0.508 0.9398)
			(stroke
				(width 0.1524)
				(type default)
			)
			(layer "F.SilkS")
		)
		(fp_line
			(start 0.508 -0.9398)
			(end -0.508 -0.9398)
			(stroke
				(width 0.1524)
				(type default)
			)
			(layer "F.SilkS")
		)
		(fp_rect
			(start -0.508 0.9398)
			(end 0.508 -0.9398)
			(stroke
				(width 0)
				(type default)
			)
			(fill no)
			(layer "F.CrtYd")
		)
		(fp_rect
			(start -0.508 0.9398)
			(end 0.508 -0.9398)
			(stroke
				(width 0)
				(type default)
			)
			(fill no)
			(layer "F.Fab")
		)
		(pad "1" smd custom
			(at 0 -0.4445 270)
			(size 0.1397 0.1397)
			(layers "F.Cu" "F.Mask" "F.Paste")
			(net "P12V_A")
			(options
				(clearance outline)
				(anchor circle)
			)
			(primitives
				(gr_poly
					(pts
						(arc
							(start -0.1778 -0.2794)
							(mid -0.249642 -0.249642)
							(end -0.2794 -0.1778)
						)
						(arc
							(start -0.2794 0.1778)
							(mid -0.249642 0.249642)
							(end -0.1778 0.2794)
						)
						(arc
							(start 0.1778 0.2794)
							(mid 0.249642 0.249642)
							(end 0.2794 0.1778)
						)
						(arc
							(start 0.2794 -0.1778)
							(mid 0.249642 -0.249642)
							(end 0.1778 -0.2794)
						)
					)
					(width 0)
					(fill yes)
				)
			)
		)
		(pad "2" smd custom
			(at 0 0.4445 270)
			(size 0.1397 0.1397)
			(layers "F.Cu" "F.Mask" "F.Paste")
			(net "SW_HDD_P20")
			(options
				(clearance outline)
				(anchor circle)
			)
			(primitives
				(gr_poly
					(pts
						(arc
							(start -0.1778 -0.2794)
							(mid -0.249642 -0.249642)
							(end -0.2794 -0.1778)
						)
						(arc
							(start -0.2794 0.1778)
							(mid -0.249642 0.249642)
							(end -0.1778 0.2794)
						)
						(arc
							(start 0.1778 0.2794)
							(mid 0.249642 0.249642)
							(end 0.2794 0.1778)
						)
						(arc
							(start 0.2794 -0.1778)
							(mid 0.249642 -0.249642)
							(end 0.1778 -0.2794)
						)
					)
					(width 0)
					(fill yes)
				)
			)
		)
	)
	(footprint ""
		(layer "F.Cu")
		(at 394.56995 -188.954918 180)
		(property "Reference" "C305"
			(at 0 0 180)
			(layer "F.SilkS")
			(hide yes)
			(effects
				(font
					(size 1.27 1.27)
				)
			)
		)
		(property "Value" "SC4D7U25V5KX-1-GP"
			(at -0.0762 -6.1214 180)
			(unlocked yes)
			(layer "F.Fab")
			(hide yes)
			(effects
				(font
					(size 1.016 1.016)
					(thickness 0.1524)
				)
			)
		)
		(property "Device Type" "C805H58"
			(at -0.0762 -8.1534 180)
			(unlocked yes)
			(layer "F.Fab")
			(hide yes)
			(effects
				(font
					(size 1.016 1.016)
					(thickness 0.1524)
				)
			)
		)
		(duplicate_pad_numbers_are_jumpers no)
		(fp_line
			(start 0.635 0)
			(end -0.635 0)
			(stroke
				(width 0.508)
				(type default)
			)
			(layer "F.SilkS")
		)
		(fp_rect
			(start -0.9652 1.778)
			(end 0.9652 -1.778)
			(stroke
				(width 0)
				(type default)
			)
			(fill no)
			(layer "F.CrtYd")
		)
		(fp_poly
			(pts
				(xy -0.9652 -1.778) (xy 0.9652 -1.778) (xy 0.9652 1.778) (xy -0.9652 1.778)
			)
			(stroke
				(width 0)
				(type default)
			)
			(fill no)
			(layer "F.Fab")
		)
		(pad "1" smd rect
			(at 0 -0.9652 180)
			(size 1.397 1.143)
			(layers "F.Cu" "F.Mask" "F.Paste")
			(net "P12V_HDD20")
		)
		(pad "2" smd rect
			(at 0 0.9652 180)
			(size 1.397 1.143)
			(layers "F.Cu" "F.Mask" "F.Paste")
			(net "GND")
		)
	)
	(footprint ""
		(layer "F.Cu")
		(at 365.052102 -73.954894 180)
		(property "Reference" "C448"
			(at 0 0 180)
			(layer "F.SilkS")
			(hide yes)
			(effects
				(font
					(size 1.27 1.27)
				)
			)
		)
		(property "Value" "SC4D7U25V5KX-1-GP"
			(at -0.0762 -6.1214 180)
			(unlocked yes)
			(layer "F.Fab")
			(hide yes)
			(effects
				(font
					(size 1.016 1.016)
					(thickness 0.1524)
				)
			)
		)
		(property "Device Type" "C805H58"
			(at -0.0762 -8.1534 180)
			(unlocked yes)
			(layer "F.Fab")
			(hide yes)
			(effects
				(font
					(size 1.016 1.016)
					(thickness 0.1524)
				)
			)
		)
		(duplicate_pad_numbers_are_jumpers no)
		(fp_line
			(start 0.635 0)
			(end -0.635 0)
			(stroke
				(width 0.508)
				(type default)
			)
			(layer "F.SilkS")
		)
		(fp_rect
			(start -0.9652 1.778)
			(end 0.9652 -1.778)
			(stroke
				(width 0)
				(type default)
			)
			(fill no)
			(layer "F.CrtYd")
		)
		(fp_poly
			(pts
				(xy -0.9652 -1.778) (xy 0.9652 -1.778) (xy 0.9652 1.778) (xy -0.9652 1.778)
			)
			(stroke
				(width 0)
				(type default)
			)
			(fill no)
			(layer "F.Fab")
		)
		(pad "1" smd rect
			(at 0 -0.9652 180)
			(size 1.397 1.143)
			(layers "F.Cu" "F.Mask" "F.Paste")
			(net "P12V_HDD31")
		)
		(pad "2" smd rect
			(at 0 0.9652 180)
			(size 1.397 1.143)
			(layers "F.Cu" "F.Mask" "F.Paste")
			(net "GND")
		)
	)
)
